(kicad_pcb
	(version 20260206)
	(generator "pcbnew")
	(generator_version "10.0")
	(general
		(thickness 1.6)
		(legacy_teardrops no)
	)
	(paper "A4")
	(title_block
		(title "9054_F0T_PDB_BD_GPU_F_V04_1213_1550_OCP.brd")
		(comment 1 "Grand Teton / footprints 280-284 of 608")
	)
	(layers
		(0 "F.Cu" signal "TOP")
		(4 "In1.Cu" signal "GND")
		(6 "In2.Cu" signal "IN1")
		(8 "In3.Cu" signal "GND1")
		(10 "In4.Cu" signal "VCC")
		(12 "In5.Cu" signal "VCC1")
		(14 "In6.Cu" signal "GND2")
		(16 "In7.Cu" signal "IN2")
		(18 "In8.Cu" signal "GND3")
		(2 "B.Cu" signal "BOTTOM")
		(9 "F.Adhes" user "F.Adhesive")
		(11 "B.Adhes" user "B.Adhesive")
		(13 "F.Paste" user "Package Geometry/Pastemask Top")
		(15 "B.Paste" user "Package Geometry/Pastemask Bottom")
		(5 "F.SilkS" user "Ref Des/Silkscreen Top")
		(7 "B.SilkS" user "Ref Des/Silkscreen Bottom")
		(1 "F.Mask" user "Board Geometry/Soldermask Top")
		(3 "B.Mask" user "Board Geometry/Soldermask Bottom")
		(17 "Dwgs.User" user "User.Drawings")
		(19 "Cmts.User" user "User.Comments")
		(21 "Eco1.User" user "User.Eco1")
		(23 "Eco2.User" user "User.Eco2")
		(25 "Edge.Cuts" user "Board Geometry/Outline")
		(27 "Margin" user)
		(31 "F.CrtYd" user "Package Geometry/Place Bound Top")
		(29 "B.CrtYd" user "Package Geometry/Place Bound Bottom")
		(35 "F.Fab" user "Ref Des/Assembly Top")
		(33 "B.Fab" user "Ref Des/Assembly Bottom")
	)
	(footprint ""
		(layer "F.Cu")
		(at 450.42074 -84.409788)
		(property "Reference" "PC53"
			(at 0 0 0)
			(layer "F.SilkS")
			(hide yes)
			(effects
				(font
					(size 1.27 1.27)
				)
			)
		)
		(property "Value" ""
			(at 0 0 0)
			(layer "F.Fab")
			(effects
				(font
					(size 1.27 1.27)
				)
			)
		)
		(duplicate_pad_numbers_are_jumpers no)
		(fp_line
			(start -0.7874 -0.4064)
			(end 0.7874 -0.4064)
			(stroke
				(width 0.1524)
				(type default)
			)
			(layer "F.SilkS")
		)
		(fp_line
			(start -0.7874 0.4064)
			(end -0.7874 -0.4064)
			(stroke
				(width 0.1524)
				(type default)
			)
			(layer "F.SilkS")
		)
		(fp_line
			(start 0.7874 -0.4064)
			(end 0.7874 0.4064)
			(stroke
				(width 0.1524)
				(type default)
			)
			(layer "F.SilkS")
		)
		(fp_line
			(start 0.7874 0.4064)
			(end -0.7874 0.4064)
			(stroke
				(width 0.1524)
				(type default)
			)
			(layer "F.SilkS")
		)
		(fp_line
			(start -0.67945 -0.305054)
			(end -0.12065 -0.305054)
			(stroke
				(width 0.1)
				(type default)
			)
			(layer "F.Fab")
		)
		(fp_line
			(start -0.67945 0.3048)
			(end -0.67945 -0.305054)
			(stroke
				(width 0.1)
				(type default)
			)
			(layer "F.Fab")
		)
		(fp_line
			(start -0.12065 -0.305054)
			(end -0.12065 -0.2794)
			(stroke
				(width 0.1)
				(type default)
			)
			(layer "F.Fab")
		)
		(fp_line
			(start -0.12065 -0.2794)
			(end 0.12065 -0.2794)
			(stroke
				(width 0.1)
				(type default)
			)
			(layer "F.Fab")
		)
		(fp_line
			(start -0.12065 0.2794)
			(end -0.12065 0.3048)
			(stroke
				(width 0.1)
				(type default)
			)
			(layer "F.Fab")
		)
		(fp_line
			(start -0.12065 0.3048)
			(end -0.67945 0.3048)
			(stroke
				(width 0.1)
				(type default)
			)
			(layer "F.Fab")
		)
		(fp_line
			(start 0.120396 0.2794)
			(end -0.12065 0.2794)
			(stroke
				(width 0.1)
				(type default)
			)
			(layer "F.Fab")
		)
		(fp_line
			(start 0.120396 0.3048)
			(end 0.120396 0.2794)
			(stroke
				(width 0.1)
				(type default)
			)
			(layer "F.Fab")
		)
		(fp_line
			(start 0.12065 -0.3048)
			(end 0.67945 -0.3048)
			(stroke
				(width 0.1)
				(type default)
			)
			(layer "F.Fab")
		)
		(fp_line
			(start 0.12065 -0.2794)
			(end 0.12065 -0.3048)
			(stroke
				(width 0.1)
				(type default)
			)
			(layer "F.Fab")
		)
		(fp_line
			(start 0.67945 -0.3048)
			(end 0.67945 0.3048)
			(stroke
				(width 0.1)
				(type default)
			)
			(layer "F.Fab")
		)
		(fp_line
			(start 0.67945 0.3048)
			(end 0.120396 0.3048)
			(stroke
				(width 0.1)
				(type default)
			)
			(layer "F.Fab")
		)
		(pad "1" smd circle
			(at -0.40005 0)
			(size 0 0)
			(layers "F.Cu" "F.Mask" "F.Paste")
			(net "P3V3_HPDB_REF")
		)
		(pad "2" smd circle
			(at 0.40005 0)
			(size 0 0)
			(layers "F.Cu" "F.Mask" "F.Paste")
			(net "GND")
		)
	)
	(footprint ""
		(layer "F.Cu")
		(at 281.0764 -76.327)
		(property "Reference" "PR36"
			(at 0 0 0)
			(layer "F.SilkS")
			(hide yes)
			(effects
				(font
					(size 1.27 1.27)
				)
			)
		)
		(property "Value" ""
			(at 0 0 0)
			(layer "F.Fab")
			(effects
				(font
					(size 1.27 1.27)
				)
			)
		)
		(duplicate_pad_numbers_are_jumpers no)
		(fp_line
			(start -0.7874 -0.4064)
			(end 0.7874 -0.4064)
			(stroke
				(width 0.1524)
				(type default)
			)
			(layer "F.SilkS")
		)
		(fp_line
			(start -0.7874 0.4064)
			(end -0.7874 -0.4064)
			(stroke
				(width 0.1524)
				(type default)
			)
			(layer "F.SilkS")
		)
		(fp_line
			(start 0.7874 -0.4064)
			(end 0.7874 0.4064)
			(stroke
				(width 0.1524)
				(type default)
			)
			(layer "F.SilkS")
		)
		(fp_line
			(start 0.7874 0.4064)
			(end -0.7874 0.4064)
			(stroke
				(width 0.1524)
				(type default)
			)
			(layer "F.SilkS")
		)
		(fp_line
			(start -0.67945 -0.305054)
			(end -0.12065 -0.305054)
			(stroke
				(width 0.1)
				(type default)
			)
			(layer "F.Fab")
		)
		(fp_line
			(start -0.67945 0.3048)
			(end -0.67945 -0.305054)
			(stroke
				(width 0.1)
				(type default)
			)
			(layer "F.Fab")
		)
		(fp_line
			(start -0.12065 -0.305054)
			(end -0.12065 -0.2794)
			(stroke
				(width 0.1)
				(type default)
			)
			(layer "F.Fab")
		)
		(fp_line
			(start -0.12065 -0.2794)
			(end 0.12065 -0.2794)
			(stroke
				(width 0.1)
				(type default)
			)
			(layer "F.Fab")
		)
		(fp_line
			(start -0.12065 0.2794)
			(end -0.12065 0.3048)
			(stroke
				(width 0.1)
				(type default)
			)
			(layer "F.Fab")
		)
		(fp_line
			(start -0.12065 0.3048)
			(end -0.67945 0.3048)
			(stroke
				(width 0.1)
				(type default)
			)
			(layer "F.Fab")
		)
		(fp_line
			(start 0.120396 0.2794)
			(end -0.12065 0.2794)
			(stroke
				(width 0.1)
				(type default)
			)
			(layer "F.Fab")
		)
		(fp_line
			(start 0.120396 0.3048)
			(end 0.120396 0.2794)
			(stroke
				(width 0.1)
				(type default)
			)
			(layer "F.Fab")
		)
		(fp_line
			(start 0.12065 -0.3048)
			(end 0.67945 -0.3048)
			(stroke
				(width 0.1)
				(type default)
			)
			(layer "F.Fab")
		)
		(fp_line
			(start 0.12065 -0.2794)
			(end 0.12065 -0.3048)
			(stroke
				(width 0.1)
				(type default)
			)
			(layer "F.Fab")
		)
		(fp_line
			(start 0.67945 -0.3048)
			(end 0.67945 0.3048)
			(stroke
				(width 0.1)
				(type default)
			)
			(layer "F.Fab")
		)
		(fp_line
			(start 0.67945 0.3048)
			(end 0.120396 0.3048)
			(stroke
				(width 0.1)
				(type default)
			)
			(layer "F.Fab")
		)
		(pad "1" smd circle
			(at -0.40005 0)
			(size 0 0)
			(layers "F.Cu" "F.Mask" "F.Paste")
			(net "P52V_HS1_ESTART")
		)
		(pad "2" smd circle
			(at 0.40005 0)
			(size 0 0)
			(layers "F.Cu" "F.Mask" "F.Paste")
			(net "GND_FIELD_SIGNAL")
		)
	)
	(footprint ""
		(layer "F.Cu")
		(at 438.3278 -25.146 180)
		(property "Reference" "R66"
			(at 0 0 180)
			(layer "F.SilkS")
			(hide yes)
			(effects
				(font
					(size 1.27 1.27)
				)
			)
		)
		(property "Value" ""
			(at 0 0 180)
			(layer "F.Fab")
			(effects
				(font
					(size 1.27 1.27)
				)
			)
		)
		(duplicate_pad_numbers_are_jumpers no)
		(fp_line
			(start 0.7874 0.4064)
			(end -0.7874 0.4064)
			(stroke
				(width 0.1524)
				(type default)
			)
			(layer "F.SilkS")
		)
		(fp_line
			(start 0.7874 -0.4064)
			(end 0.7874 0.4064)
			(stroke
				(width 0.1524)
				(type default)
			)
			(layer "F.SilkS")
		)
		(fp_line
			(start -0.7874 0.4064)
			(end -0.7874 -0.4064)
			(stroke
				(width 0.1524)
				(type default)
			)
			(layer "F.SilkS")
		)
		(fp_line
			(start -0.7874 -0.4064)
			(end 0.7874 -0.4064)
			(stroke
				(width 0.1524)
				(type default)
			)
			(layer "F.SilkS")
		)
		(fp_line
			(start 0.67945 0.3048)
			(end 0.120396 0.3048)
			(stroke
				(width 0.1)
				(type default)
			)
			(layer "F.Fab")
		)
		(fp_line
			(start 0.67945 -0.3048)
			(end 0.67945 0.3048)
			(stroke
				(width 0.1)
				(type default)
			)
			(layer "F.Fab")
		)
		(fp_line
			(start 0.12065 -0.2794)
			(end 0.12065 -0.3048)
			(stroke
				(width 0.1)
				(type default)
			)
			(layer "F.Fab")
		)
		(fp_line
			(start 0.12065 -0.3048)
			(end 0.67945 -0.3048)
			(stroke
				(width 0.1)
				(type default)
			)
			(layer "F.Fab")
		)
		(fp_line
			(start 0.120396 0.3048)
			(end 0.120396 0.2794)
			(stroke
				(width 0.1)
				(type default)
			)
			(layer "F.Fab")
		)
		(fp_line
			(start 0.120396 0.2794)
			(end -0.12065 0.2794)
			(stroke
				(width 0.1)
				(type default)
			)
			(layer "F.Fab")
		)
		(fp_line
			(start -0.12065 0.3048)
			(end -0.67945 0.3048)
			(stroke
				(width 0.1)
				(type default)
			)
			(layer "F.Fab")
		)
		(fp_line
			(start -0.12065 0.2794)
			(end -0.12065 0.3048)
			(stroke
				(width 0.1)
				(type default)
			)
			(layer "F.Fab")
		)
		(fp_line
			(start -0.12065 -0.2794)
			(end 0.12065 -0.2794)
			(stroke
				(width 0.1)
				(type default)
			)
			(layer "F.Fab")
		)
		(fp_line
			(start -0.12065 -0.305054)
			(end -0.12065 -0.2794)
			(stroke
				(width 0.1)
				(type default)
			)
			(layer "F.Fab")
		)
		(fp_line
			(start -0.67945 0.3048)
			(end -0.67945 -0.305054)
			(stroke
				(width 0.1)
				(type default)
			)
			(layer "F.Fab")
		)
		(fp_line
			(start -0.67945 -0.305054)
			(end -0.12065 -0.305054)
			(stroke
				(width 0.1)
				(type default)
			)
			(layer "F.Fab")
		)
		(pad "1" smd circle
			(at -0.40005 0 180)
			(size 0 0)
			(layers "F.Cu" "F.Mask" "F.Paste")
			(net "GND")
		)
		(pad "2" smd circle
			(at 0.40005 0 180)
			(size 0 0)
			(layers "F.Cu" "F.Mask" "F.Paste")
			(net "FRU_ADDR0")
		)
	)
	(footprint ""
		(layer "F.Cu")
		(at 433.705 -50.038 -90)
		(property "Reference" "R5898"
			(at 0 0 270)
			(layer "F.SilkS")
			(hide yes)
			(effects
				(font
					(size 1.27 1.27)
				)
			)
		)
		(property "Value" ""
			(at 0 0 270)
			(layer "F.Fab")
			(effects
				(font
					(size 1.27 1.27)
				)
			)
		)
		(duplicate_pad_numbers_are_jumpers no)
		(fp_line
			(start -0.7874 0.4064)
			(end -0.7874 -0.4064)
			(stroke
				(width 0.1524)
				(type default)
			)
			(layer "F.SilkS")
		)
		(fp_line
			(start 0.7874 0.4064)
			(end -0.7874 0.4064)
			(stroke
				(width 0.1524)
				(type default)
			)
			(layer "F.SilkS")
		)
		(fp_line
			(start -0.7874 -0.4064)
			(end 0.7874 -0.4064)
			(stroke
				(width 0.1524)
				(type default)
			)
			(layer "F.SilkS")
		)
		(fp_line
			(start 0.7874 -0.4064)
			(end 0.7874 0.4064)
			(stroke
				(width 0.1524)
				(type default)
			)
			(layer "F.SilkS")
		)
		(fp_line
			(start -0.67945 0.3048)
			(end -0.67945 -0.305054)
			(stroke
				(width 0.1)
				(type default)
			)
			(layer "F.Fab")
		)
		(fp_line
			(start -0.12065 0.3048)
			(end -0.67945 0.3048)
			(stroke
				(width 0.1)
				(type default)
			)
			(layer "F.Fab")
		)
		(fp_line
			(start 0.120396 0.3048)
			(end 0.120396 0.2794)
			(stroke
				(width 0.1)
				(type default)
			)
			(layer "F.Fab")
		)
		(fp_line
			(start 0.67945 0.3048)
			(end 0.120396 0.3048)
			(stroke
				(width 0.1)
				(type default)
			)
			(layer "F.Fab")
		)
		(fp_line
			(start -0.12065 0.2794)
			(end -0.12065 0.3048)
			(stroke
				(width 0.1)
				(type default)
			)
			(layer "F.Fab")
		)
		(fp_line
			(start 0.120396 0.2794)
			(end -0.12065 0.2794)
			(stroke
				(width 0.1)
				(type default)
			)
			(layer "F.Fab")
		)
		(fp_line
			(start -0.12065 -0.2794)
			(end 0.12065 -0.2794)
			(stroke
				(width 0.1)
				(type default)
			)
			(layer "F.Fab")
		)
		(fp_line
			(start 0.12065 -0.2794)
			(end 0.12065 -0.3048)
			(stroke
				(width 0.1)
				(type default)
			)
			(layer "F.Fab")
		)
		(fp_line
			(start 0.12065 -0.3048)
			(end 0.67945 -0.3048)
			(stroke
				(width 0.1)
				(type default)
			)
			(layer "F.Fab")
		)
		(fp_line
			(start 0.67945 -0.3048)
			(end 0.67945 0.3048)
			(stroke
				(width 0.1)
				(type default)
			)
			(layer "F.Fab")
		)
		(fp_line
			(start -0.67945 -0.305054)
			(end -0.12065 -0.305054)
			(stroke
				(width 0.1)
				(type default)
			)
			(layer "F.Fab")
		)
		(fp_line
			(start -0.12065 -0.305054)
			(end -0.12065 -0.2794)
			(stroke
				(width 0.1)
				(type default)
			)
			(layer "F.Fab")
		)
		(pad "1" smd circle
			(at -0.40005 0 270)
			(size 0 0)
			(layers "F.Cu" "F.Mask" "F.Paste")
			(net "PWRGD_P52V_HS_PG_R2")
		)
		(pad "2" smd circle
			(at 0.40005 0 270)
			(size 0 0)
			(layers "F.Cu" "F.Mask" "F.Paste")
			(net "PWRGD_P52V_HS_PG")
		)
	)
	(footprint ""
		(layer "F.Cu")
		(at 446.333372 -85.257132 180)
		(property "Reference" "PU5"
			(at 2.315972 -3.241802 0)
			(unlocked yes)
			(layer "F.SilkS")
			(effects
				(font
					(size 0.7874 0.5842)
					(thickness 0.1524)
				)
				(justify left)
			)
		)
		(property "Value" ""
			(at 0 0 180)
			(layer "F.Fab")
			(effects
				(font
					(size 1.27 1.27)
				)
			)
		)
		(duplicate_pad_numbers_are_jumpers no)
		(fp_line
			(start 1.549908 2.050034)
			(end 1.549908 1.9304)
			(stroke
				(width 0.1524)
				(type default)
			)
			(layer "F.SilkS")
		)
		(fp_line
			(start 1.549908 -1.9812)
			(end 1.549908 -2.050034)
			(stroke
				(width 0.1524)
				(type default)
			)
			(layer "F.SilkS")
		)
		(fp_line
			(start 1.549908 -2.050034)
			(end 0.5842 -2.050034)
			(stroke
				(width 0.1524)
				(type default)
			)
			(layer "F.SilkS")
		)
		(fp_line
			(start 0 2.050034)
			(end 1.549908 2.050034)
			(stroke
				(width 0.1524)
				(type default)
			)
			(layer "F.SilkS")
		)
		(fp_line
			(start -0.5842 -2.050034)
			(end -1.549908 -2.050034)
			(stroke
				(width 0.1524)
				(type default)
			)
			(layer "F.SilkS")
		)
		(fp_line
			(start -1.549908 2.050034)
			(end -0.5842 2.050034)
			(stroke
				(width 0.1524)
				(type default)
			)
			(layer "F.SilkS")
		)
		(fp_line
			(start -1.549908 1.9812)
			(end -1.549908 2.050034)
			(stroke
				(width 0.1524)
				(type default)
			)
			(layer "F.SilkS")
		)
		(fp_line
			(start -1.549908 -2.050034)
			(end -1.549908 -1.9812)
			(stroke
				(width 0.1524)
				(type default)
			)
			(layer "F.SilkS")
		)
		(fp_poly
			(pts
				(xy -2.9464 -2.208022) (xy -2.9464 -1.192022) (xy -1.9304 -1.700022)
			)
			(stroke
				(width 0)
				(type default)
			)
			(fill yes)
			(layer "F.SilkS")
		)
		(fp_line
			(start 1.549908 2.050034)
			(end 1.549908 -2.050034)
			(stroke
				(width 0.1)
				(type default)
			)
			(layer "F.Fab")
		)
		(fp_line
			(start 1.549908 -2.050034)
			(end -1.549908 -2.050034)
			(stroke
				(width 0.1)
				(type default)
			)
			(layer "F.Fab")
		)
		(fp_line
			(start -1.549908 2.050034)
			(end 1.549908 2.050034)
			(stroke
				(width 0.1)
				(type default)
			)
			(layer "F.Fab")
		)
		(fp_line
			(start -1.549908 -2.050034)
			(end -1.549908 2.050034)
			(stroke
				(width 0.1)
				(type default)
			)
			(layer "F.Fab")
		)
		(fp_poly
			(pts
				(xy -2.9464 -2.208022) (xy -2.9464 -1.192022) (xy -1.9304 -1.700022)
			)
			(stroke
				(width 0)
				(type default)
			)
			(fill yes)
			(layer "F.Fab")
		)
		(pad "1" smd circle
			(at -1.35001 -1.700022 180)
			(size 0 0)
			(layers "F.Cu" "F.Mask" "F.Paste")
			(net "SW_P3V3_HPDB_BT")
		)
		(pad "2" smd rect
			(at -1.400048 -1.199896 270)
			(size 0.1778 0.8128)
			(layers "F.Cu" "F.Mask" "F.Paste")
			(net "GND")
		)
		(pad "3" smd rect
			(at -1.400048 -0.8001 270)
			(size 0.1778 0.8128)
			(layers "F.Cu" "F.Mask" "F.Paste")
			(net "P3V3_HPDB_CS")
		)
		(pad "4" smd rect
			(at -1.400048 -0.40005 270)
			(size 0.1778 0.8128)
			(layers "F.Cu" "F.Mask" "F.Paste")
			(net "GND")
		)
		(pad "5" smd rect
			(at -1.400048 0 270)
			(size 0.1778 0.8128)
			(layers "F.Cu" "F.Mask" "F.Paste")
			(net "P3V3_HPDB_REF")
		)
		(pad "6" smd rect
			(at -1.400048 0.40005 270)
			(size 0.1778 0.8128)
			(layers "F.Cu" "F.Mask" "F.Paste")
			(net "GND")
		)
		(pad "7" smd rect
			(at -1.400048 0.8001 270)
			(size 0.1778 0.8128)
			(layers "F.Cu" "F.Mask" "F.Paste")
			(net "P3V3_HPDB_FB")
		)
		(pad "8" smd rect
			(at -1.400048 1.199896 270)
			(size 0.1778 0.8128)
			(layers "F.Cu" "F.Mask" "F.Paste")
			(net "P3V3_HPDB_EN")
		)
		(pad "9" smd rect
			(at -1.400048 1.700022 270)
			(size 0.3048 0.8128)
			(layers "F.Cu" "F.Mask" "F.Paste")
			(net "P3V3_HPDB_PG_R")
		)
		(pad "10" smd rect
			(at -0.299974 1.299972 180)
			(size 0.3048 2.0066)
			(layers "F.Cu" "F.Mask" "F.Paste")
			(net "SW_P3V3_HPDB_FLT")
		)
		(pad "11_18" smd circle
			(at 1.175004 0.275082 180)
			(size 0 0)
			(layers "F.Cu" "F.Mask" "F.Paste")
			(net "GND")
		)
		(pad "19" smd rect
			(at 1.400048 -1.700022 90)
			(size 0.3048 0.8128)
			(layers "F.Cu" "F.Mask" "F.Paste")
			(net "P3V3_HPDB_VCC")
		)
		(pad "20" smd rect
			(at 0.299974 -1.299972 180)
			(size 0.3048 2.0066)
			(layers "F.Cu" "F.Mask" "F.Paste")
			(net "SW_P3V3_HPDB_PH")
		)
		(pad "21" smd rect
			(at -0.299974 -1.299972 180)
			(size 0.3048 2.0066)
			(layers "F.Cu" "F.Mask" "F.Paste")
			(net "SW_P3V3_HPDB_FLT")
		)
	)
)
